# SCM (Grand Teton) — schematic netlist excerpt (pin names and nets, part order shuffled) for the footprints in the layout excerpt that follows; sources: Cadence DE-HDL packaged netlist, KiCad conversion of 12092022_DA0F0TMDCD0_F0T_Management_Board_D_brd_V3_OCP.brd

R394  Q_RES  33.2 1% CHIP  pkg 0402LF  page 12 : A = SMB_BMC_MM2_R_SDA ; B = SMB_BMC_MM2_SDA
R362  Q_RES  120 1% CHIP  pkg 0402LF  page 20 : A = M_BMC_DDR4_MA<11> ; B = P1V2_AUX

(kicad_pcb
	(version 20260206)
	(generator "pcbnew")
	(generator_version "10.0")
	(general
		(thickness 1.6)
		(legacy_teardrops no)
	)
	(paper "A4")
	(title_block
		(title "12092022_DA0F0TMDCD0_F0T_Management_Board_D_brd_V3_OCP.brd")
		(comment 1 "Grand Teton / footprints 1008-1009 of 1440")
	)
	(layers
		(0 "F.Cu" signal "TOP")
		(4 "In1.Cu" signal "GND")
		(6 "In2.Cu" signal "IN1")
		(8 "In3.Cu" signal "GND1")
		(10 "In4.Cu" signal "IN2")
		(12 "In5.Cu" signal "VCC")
		(14 "In6.Cu" signal "VCC1")
		(16 "In7.Cu" signal "IN3")
		(18 "In8.Cu" signal "GND2")
		(20 "In9.Cu" signal "IN4")
		(22 "In10.Cu" signal "GND3")
		(2 "B.Cu" signal "BOTTOM")
		(9 "F.Adhes" user "F.Adhesive")
		(11 "B.Adhes" user "B.Adhesive")
		(13 "F.Paste" user "Package Geometry/Pastemask Top")
		(15 "B.Paste" user "Package Geometry/Pastemask Bottom")
		(5 "F.SilkS" user "Ref Des/Silkscreen Top")
		(7 "B.SilkS" user "Ref Des/Silkscreen Bottom")
		(1 "F.Mask" user "Board Geometry/Soldermask Top")
		(3 "B.Mask" user "Board Geometry/Soldermask Bottom")
		(17 "Dwgs.User" user "User.Drawings")
		(19 "Cmts.User" user "User.Comments")
		(21 "Eco1.User" user "User.Eco1")
		(23 "Eco2.User" user "User.Eco2")
		(25 "Edge.Cuts" user "Board Geometry/Outline")
		(27 "Margin" user)
		(31 "F.CrtYd" user "Package Geometry/Place Bound Top")
		(29 "B.CrtYd" user "Package Geometry/Place Bound Bottom")
		(35 "F.Fab" user "Ref Des/Assembly Top")
		(33 "B.Fab" user "Ref Des/Assembly Bottom")
	)
	(footprint ""
		(layer "B.Cu")
		(at 43.367198 -34.637726 90)
		(property "Reference" "R394"
			(at 0 0 90)
			(layer "B.SilkS")
			(hide yes)
			(effects
				(font
					(size 1.27 1.27)
				)
				(justify mirror)
			)
		)
		(property "Value" ""
			(at 0 0 90)
			(layer "B.Fab")
			(effects
				(font
					(size 1.27 1.27)
				)
				(justify mirror)
			)
		)
		(duplicate_pad_numbers_are_jumpers no)
		(fp_line
			(start 0.7874 -0.4064)
			(end -0.7874 -0.4064)
			(stroke
				(width 0.1524)
				(type default)
			)
			(layer "B.SilkS")
		)
		(fp_line
			(start -0.7874 -0.4064)
			(end -0.7874 0.4064)
			(stroke
				(width 0.1524)
				(type default)
			)
			(layer "B.SilkS")
		)
		(fp_line
			(start 0.7874 0.4064)
			(end 0.7874 -0.4064)
			(stroke
				(width 0.1524)
				(type default)
			)
			(layer "B.SilkS")
		)
		(fp_line
			(start -0.7874 0.4064)
			(end 0.7874 0.4064)
			(stroke
				(width 0.1524)
				(type default)
			)
			(layer "B.SilkS")
		)
		(fp_line
			(start 0.67945 -0.305054)
			(end 0.12065 -0.305054)
			(stroke
				(width 0.1)
				(type default)
			)
			(layer "B.Fab")
		)
		(fp_line
			(start 0.12065 -0.305054)
			(end 0.12065 -0.2794)
			(stroke
				(width 0.1)
				(type default)
			)
			(layer "B.Fab")
		)
		(fp_line
			(start -0.12065 -0.3048)
			(end -0.67945 -0.3048)
			(stroke
				(width 0.1)
				(type default)
			)
			(layer "B.Fab")
		)
		(fp_line
			(start -0.67945 -0.3048)
			(end -0.67945 0.3048)
			(stroke
				(width 0.1)
				(type default)
			)
			(layer "B.Fab")
		)
		(fp_line
			(start 0.12065 -0.2794)
			(end -0.12065 -0.2794)
			(stroke
				(width 0.1)
				(type default)
			)
			(layer "B.Fab")
		)
		(fp_line
			(start -0.12065 -0.2794)
			(end -0.12065 -0.3048)
			(stroke
				(width 0.1)
				(type default)
			)
			(layer "B.Fab")
		)
		(fp_line
			(start 0.12065 0.2794)
			(end 0.12065 0.3048)
			(stroke
				(width 0.1)
				(type default)
			)
			(layer "B.Fab")
		)
		(fp_line
			(start -0.120396 0.2794)
			(end 0.12065 0.2794)
			(stroke
				(width 0.1)
				(type default)
			)
			(layer "B.Fab")
		)
		(fp_line
			(start 0.67945 0.3048)
			(end 0.67945 -0.305054)
			(stroke
				(width 0.1)
				(type default)
			)
			(layer "B.Fab")
		)
		(fp_line
			(start 0.12065 0.3048)
			(end 0.67945 0.3048)
			(stroke
				(width 0.1)
				(type default)
			)
			(layer "B.Fab")
		)
		(fp_line
			(start -0.120396 0.3048)
			(end -0.120396 0.2794)
			(stroke
				(width 0.1)
				(type default)
			)
			(layer "B.Fab")
		)
		(fp_line
			(start -0.67945 0.3048)
			(end -0.120396 0.3048)
			(stroke
				(width 0.1)
				(type default)
			)
			(layer "B.Fab")
		)
		(pad "1" smd circle
			(at 0.40005 0 270)
			(size 0 0)
			(layers "B.Cu" "B.Mask" "B.Paste")
			(net "SMB_BMC_MM2_R_SDA")
		)
		(pad "2" smd circle
			(at -0.40005 0 270)
			(size 0 0)
			(layers "B.Cu" "B.Mask" "B.Paste")
			(net "SMB_BMC_MM2_SDA")
		)
	)
	(footprint ""
		(layer "B.Cu")
		(at 76.691744 -37.559488 90)
		(property "Reference" "R362"
			(at 0 0 90)
			(layer "B.SilkS")
			(hide yes)
			(effects
				(font
					(size 1.27 1.27)
				)
				(justify mirror)
			)
		)
		(property "Value" ""
			(at 0 0 90)
			(layer "B.Fab")
			(effects
				(font
					(size 1.27 1.27)
				)
				(justify mirror)
			)
		)
		(duplicate_pad_numbers_are_jumpers no)
		(fp_line
			(start 0.7874 -0.4064)
			(end -0.7874 -0.4064)
			(stroke
				(width 0.1524)
				(type default)
			)
			(layer "B.SilkS")
		)
		(fp_line
			(start -0.7874 -0.4064)
			(end -0.7874 0.4064)
			(stroke
				(width 0.1524)
				(type default)
			)
			(layer "B.SilkS")
		)
		(fp_line
			(start 0.7874 0.4064)
			(end 0.7874 -0.4064)
			(stroke
				(width 0.1524)
				(type default)
			)
			(layer "B.SilkS")
		)
		(fp_line
			(start -0.7874 0.4064)
			(end 0.7874 0.4064)
			(stroke
				(width 0.1524)
				(type default)
			)
			(layer "B.SilkS")
		)
		(fp_line
			(start 0.67945 -0.305054)
			(end 0.12065 -0.305054)
			(stroke
				(width 0.1)
				(type default)
			)
			(layer "B.Fab")
		)
		(fp_line
			(start 0.12065 -0.305054)
			(end 0.12065 -0.2794)
			(stroke
				(width 0.1)
				(type default)
			)
			(layer "B.Fab")
		)
		(fp_line
			(start -0.12065 -0.3048)
			(end -0.67945 -0.3048)
			(stroke
				(width 0.1)
				(type default)
			)
			(layer "B.Fab")
		)
		(fp_line
			(start -0.67945 -0.3048)
			(end -0.67945 0.3048)
			(stroke
				(width 0.1)
				(type default)
			)
			(layer "B.Fab")
		)
		(fp_line
			(start 0.12065 -0.2794)
			(end -0.12065 -0.2794)
			(stroke
				(width 0.1)
				(type default)
			)
			(layer "B.Fab")
		)
		(fp_line
			(start -0.12065 -0.2794)
			(end -0.12065 -0.3048)
			(stroke
				(width 0.1)
				(type default)
			)
			(layer "B.Fab")
		)
		(fp_line
			(start 0.12065 0.2794)
			(end 0.12065 0.3048)
			(stroke
				(width 0.1)
				(type default)
			)
			(layer "B.Fab")
		)
		(fp_line
			(start -0.120396 0.2794)
			(end 0.12065 0.2794)
			(stroke
				(width 0.1)
				(type default)
			)
			(layer "B.Fab")
		)
		(fp_line
			(start 0.67945 0.3048)
			(end 0.67945 -0.305054)
			(stroke
				(width 0.1)
				(type default)
			)
			(layer "B.Fab")
		)
		(fp_line
			(start 0.12065 0.3048)
			(end 0.67945 0.3048)
			(stroke
				(width 0.1)
				(type default)
			)
			(layer "B.Fab")
		)
		(fp_line
			(start -0.120396 0.3048)
			(end -0.120396 0.2794)
			(stroke
				(width 0.1)
				(type default)
			)
			(layer "B.Fab")
		)
		(fp_line
			(start -0.67945 0.3048)
			(end -0.120396 0.3048)
			(stroke
				(width 0.1)
				(type default)
			)
			(layer "B.Fab")
		)
		(pad "1" smd circle
			(at 0.40005 0 270)
			(size 0 0)
			(layers "B.Cu" "B.Mask" "B.Paste")
			(net "M_BMC_DDR4_MA<11>")
		)
		(pad "2" smd circle
			(at -0.40005 0 270)
			(size 0 0)
			(layers "B.Cu" "B.Mask" "B.Paste")
			(net "P1V2_AUX")
		)
	)
)
